(kicad_pcb
	(version 20260206)
	(generator "pcbnew")
	(generator_version "10.0")
	(general
		(thickness 1.6)
		(legacy_teardrops no)
	)
	(paper "A4")
	(title_block
		(title "03242023_DA0F0TMBIJ0_F0T_Motherboard_J_brd_V01_OCP.brd")
		(comment 1 "Grand Teton / footprints 588-592 of 6105")
	)
	(layers
		(0 "F.Cu" signal "TOP")
		(4 "In1.Cu" signal "GND")
		(6 "In2.Cu" signal "IN1")
		(8 "In3.Cu" signal "GND1")
		(10 "In4.Cu" signal "IN2")
		(12 "In5.Cu" signal "GND2")
		(14 "In6.Cu" signal "IN3")
		(16 "In7.Cu" signal "GND3")
		(18 "In8.Cu" signal "VCC")
		(20 "In9.Cu" signal "VCC1")
		(22 "In10.Cu" signal "GND4")
		(24 "In11.Cu" signal "IN4")
		(26 "In12.Cu" signal "GND5")
		(28 "In13.Cu" signal "IN5")
		(30 "In14.Cu" signal "GND6")
		(32 "In15.Cu" signal "IN6")
		(34 "In16.Cu" signal "GND7")
		(2 "B.Cu" signal "BOTTOM")
		(9 "F.Adhes" user "F.Adhesive")
		(11 "B.Adhes" user "B.Adhesive")
		(13 "F.Paste" user "Package Geometry/Pastemask Top")
		(15 "B.Paste" user "Package Geometry/Pastemask Bottom")
		(5 "F.SilkS" user "Ref Des/Silkscreen Top")
		(7 "B.SilkS" user "Ref Des/Silkscreen Bottom")
		(1 "F.Mask" user "Board Geometry/Soldermask Top")
		(3 "B.Mask" user "Board Geometry/Soldermask Bottom")
		(17 "Dwgs.User" user "User.Drawings")
		(19 "Cmts.User" user "User.Comments")
		(21 "Eco1.User" user "User.Eco1")
		(23 "Eco2.User" user "User.Eco2")
		(25 "Edge.Cuts" user "Board Geometry/Outline")
		(27 "Margin" user)
		(31 "F.CrtYd" user "Package Geometry/Place Bound Top")
		(29 "B.CrtYd" user "Package Geometry/Place Bound Bottom")
		(35 "F.Fab" user "Ref Des/Assembly Top")
		(33 "B.Fab" user "Ref Des/Assembly Bottom")
	)
	(footprint ""
		(layer "F.Cu")
		(at 204.93736 -116.804948 180)
		(property "Reference" "R4172"
			(at 0 0 180)
			(layer "F.SilkS")
			(hide yes)
			(effects
				(font
					(size 1.27 1.27)
				)
			)
		)
		(property "Value" ""
			(at 0 0 180)
			(layer "F.Fab")
			(effects
				(font
					(size 1.27 1.27)
				)
			)
		)
		(duplicate_pad_numbers_are_jumpers no)
		(fp_line
			(start 0.7874 0.4064)
			(end -0.7874 0.4064)
			(stroke
				(width 0.1524)
				(type default)
			)
			(layer "F.SilkS")
		)
		(fp_line
			(start 0.7874 -0.4064)
			(end 0.7874 0.4064)
			(stroke
				(width 0.1524)
				(type default)
			)
			(layer "F.SilkS")
		)
		(fp_line
			(start -0.7874 0.4064)
			(end -0.7874 -0.4064)
			(stroke
				(width 0.1524)
				(type default)
			)
			(layer "F.SilkS")
		)
		(fp_line
			(start -0.7874 -0.4064)
			(end 0.7874 -0.4064)
			(stroke
				(width 0.1524)
				(type default)
			)
			(layer "F.SilkS")
		)
		(fp_line
			(start 0.67945 0.3048)
			(end 0.120396 0.3048)
			(stroke
				(width 0.1)
				(type default)
			)
			(layer "F.Fab")
		)
		(fp_line
			(start 0.67945 -0.3048)
			(end 0.67945 0.3048)
			(stroke
				(width 0.1)
				(type default)
			)
			(layer "F.Fab")
		)
		(fp_line
			(start 0.12065 -0.2794)
			(end 0.12065 -0.3048)
			(stroke
				(width 0.1)
				(type default)
			)
			(layer "F.Fab")
		)
		(fp_line
			(start 0.12065 -0.3048)
			(end 0.67945 -0.3048)
			(stroke
				(width 0.1)
				(type default)
			)
			(layer "F.Fab")
		)
		(fp_line
			(start 0.120396 0.3048)
			(end 0.120396 0.2794)
			(stroke
				(width 0.1)
				(type default)
			)
			(layer "F.Fab")
		)
		(fp_line
			(start 0.120396 0.2794)
			(end -0.12065 0.2794)
			(stroke
				(width 0.1)
				(type default)
			)
			(layer "F.Fab")
		)
		(fp_line
			(start -0.12065 0.3048)
			(end -0.67945 0.3048)
			(stroke
				(width 0.1)
				(type default)
			)
			(layer "F.Fab")
		)
		(fp_line
			(start -0.12065 0.2794)
			(end -0.12065 0.3048)
			(stroke
				(width 0.1)
				(type default)
			)
			(layer "F.Fab")
		)
		(fp_line
			(start -0.12065 -0.2794)
			(end 0.12065 -0.2794)
			(stroke
				(width 0.1)
				(type default)
			)
			(layer "F.Fab")
		)
		(fp_line
			(start -0.12065 -0.305054)
			(end -0.12065 -0.2794)
			(stroke
				(width 0.1)
				(type default)
			)
			(layer "F.Fab")
		)
		(fp_line
			(start -0.67945 0.3048)
			(end -0.67945 -0.305054)
			(stroke
				(width 0.1)
				(type default)
			)
			(layer "F.Fab")
		)
		(fp_line
			(start -0.67945 -0.305054)
			(end -0.12065 -0.305054)
			(stroke
				(width 0.1)
				(type default)
			)
			(layer "F.Fab")
		)
		(pad "1" smd circle
			(at -0.40005 0 180)
			(size 0 0)
			(layers "F.Cu" "F.Mask" "F.Paste")
			(net "GPU_3V3IO_RSVD4_ISO")
		)
		(pad "2" smd circle
			(at 0.40005 0 180)
			(size 0 0)
			(layers "F.Cu" "F.Mask" "F.Paste")
			(net "GPU_3V3IO_RSVD4_ISO_R")
		)
	)
	(footprint ""
		(layer "F.Cu")
		(at 186.87034 -360.26471)
		(property "Reference" "PC1682"
			(at 0 0 0)
			(layer "F.SilkS")
			(hide yes)
			(effects
				(font
					(size 1.27 1.27)
				)
			)
		)
		(property "Value" ""
			(at 0 0 0)
			(layer "F.Fab")
			(effects
				(font
					(size 1.27 1.27)
				)
			)
		)
		(duplicate_pad_numbers_are_jumpers no)
		(fp_line
			(start -1.524 -0.762)
			(end 1.524 -0.762)
			(stroke
				(width 0.1524)
				(type default)
			)
			(layer "F.SilkS")
		)
		(fp_line
			(start -1.524 0.762)
			(end -1.524 -0.762)
			(stroke
				(width 0.1524)
				(type default)
			)
			(layer "F.SilkS")
		)
		(fp_line
			(start 1.524 -0.762)
			(end 1.524 0.762)
			(stroke
				(width 0.1524)
				(type default)
			)
			(layer "F.SilkS")
		)
		(fp_line
			(start 1.524 0.762)
			(end -1.524 0.762)
			(stroke
				(width 0.1524)
				(type default)
			)
			(layer "F.SilkS")
		)
		(fp_line
			(start -1.1049 -0.724916)
			(end -1.1049 0.724916)
			(stroke
				(width 0.1)
				(type default)
			)
			(layer "F.Fab")
		)
		(fp_line
			(start -1.1049 0.724916)
			(end 1.1049 0.724916)
			(stroke
				(width 0.1)
				(type default)
			)
			(layer "F.Fab")
		)
		(fp_line
			(start 1.1049 -0.724916)
			(end -1.1049 -0.724916)
			(stroke
				(width 0.1)
				(type default)
			)
			(layer "F.Fab")
		)
		(fp_line
			(start 1.1049 0.724916)
			(end 1.1049 -0.724916)
			(stroke
				(width 0.1)
				(type default)
			)
			(layer "F.Fab")
		)
		(pad "1" smd rect
			(at -0.889 0 180)
			(size 1.016 1.27)
			(layers "F.Cu" "F.Mask" "F.Paste")
			(net "SW_P12V_PVCCFA_EHV_FIVRA_CPU1_R")
		)
		(pad "2" smd rect
			(at 0.889 0 180)
			(size 1.016 1.27)
			(layers "F.Cu" "F.Mask" "F.Paste")
			(net "GND")
		)
	)
	(footprint ""
		(layer "F.Cu")
		(at 418.2618 -16.088614 90)
		(property "Reference" "C859"
			(at 0 0 90)
			(layer "F.SilkS")
			(hide yes)
			(effects
				(font
					(size 1.27 1.27)
				)
			)
		)
		(property "Value" ""
			(at 0 0 90)
			(layer "F.Fab")
			(effects
				(font
					(size 1.27 1.27)
				)
			)
		)
		(duplicate_pad_numbers_are_jumpers no)
		(fp_line
			(start 0.299974 -0.150114)
			(end 0.299974 0.150114)
			(stroke
				(width 0.1)
				(type default)
			)
			(layer "F.Fab")
		)
		(fp_line
			(start -0.299974 -0.150114)
			(end 0.299974 -0.150114)
			(stroke
				(width 0.1)
				(type default)
			)
			(layer "F.Fab")
		)
		(fp_line
			(start 0.299974 0.150114)
			(end -0.299974 0.150114)
			(stroke
				(width 0.1)
				(type default)
			)
			(layer "F.Fab")
		)
		(fp_line
			(start -0.299974 0.150114)
			(end -0.299974 -0.150114)
			(stroke
				(width 0.1)
				(type default)
			)
			(layer "F.Fab")
		)
		(pad "1" smd rect
			(at -0.2667 0 90)
			(size 0.3048 0.381)
			(layers "F.Cu" "F.Mask" "F.Paste")
			(net "P5E_CPU0_PE1_TX_C_DP<5>")
		)
		(pad "2" smd rect
			(at 0.2667 0 90)
			(size 0.3048 0.381)
			(layers "F.Cu" "F.Mask" "F.Paste")
			(net "P5E_CPU0_PE1_TX_DP<5>")
		)
	)
	(footprint ""
		(layer "F.Cu")
		(at 253.86157 -50.366422 180)
		(property "Reference" "PU292"
			(at 7.20217 0.018034 0)
			(unlocked yes)
			(layer "F.SilkS")
			(effects
				(font
					(size 0.7874 0.5842)
					(thickness 0.1524)
				)
				(justify left)
			)
		)
		(property "Value" ""
			(at 0 0 180)
			(layer "F.Fab")
			(effects
				(font
					(size 1.27 1.27)
				)
			)
		)
		(duplicate_pad_numbers_are_jumpers no)
		(fp_line
			(start 1.549908 2.549906)
			(end 1.549908 2.253996)
			(stroke
				(width 0.1524)
				(type default)
			)
			(layer "F.SilkS")
		)
		(fp_line
			(start 1.549908 -2.253996)
			(end 1.549908 -2.549906)
			(stroke
				(width 0.1524)
				(type default)
			)
			(layer "F.SilkS")
		)
		(fp_line
			(start 1.549908 -2.549906)
			(end 0.752094 -2.549906)
			(stroke
				(width 0.1524)
				(type default)
			)
			(layer "F.SilkS")
		)
		(fp_line
			(start 0.753872 2.549906)
			(end 1.549908 2.549906)
			(stroke
				(width 0.1524)
				(type default)
			)
			(layer "F.SilkS")
		)
		(fp_line
			(start 0.2413 -2.549906)
			(end -0.2413 -2.549906)
			(stroke
				(width 0.1524)
				(type default)
			)
			(layer "F.SilkS")
		)
		(fp_line
			(start -0.245872 2.549906)
			(end 0.245872 2.549906)
			(stroke
				(width 0.1524)
				(type default)
			)
			(layer "F.SilkS")
		)
		(fp_line
			(start -0.752094 -2.549906)
			(end -1.549908 -2.549906)
			(stroke
				(width 0.1524)
				(type default)
			)
			(layer "F.SilkS")
		)
		(fp_line
			(start -1.549908 2.549906)
			(end -0.753872 2.549906)
			(stroke
				(width 0.1524)
				(type default)
			)
			(layer "F.SilkS")
		)
		(fp_line
			(start -1.549908 2.253996)
			(end -1.549908 2.549906)
			(stroke
				(width 0.1524)
				(type default)
			)
			(layer "F.SilkS")
		)
		(fp_line
			(start -1.549908 -2.549906)
			(end -1.549908 -2.251964)
			(stroke
				(width 0.1524)
				(type default)
			)
			(layer "F.SilkS")
		)
		(fp_poly
			(pts
				(xy -2.60731 -2.833878) (xy -1.869948 -3.259582) (xy -1.812798 -2.309368)
			)
			(stroke
				(width 0)
				(type default)
			)
			(fill yes)
			(layer "F.SilkS")
		)
		(fp_line
			(start 1.549908 2.549906)
			(end 1.549908 -2.549906)
			(stroke
				(width 0.1)
				(type default)
			)
			(layer "F.Fab")
		)
		(fp_line
			(start 1.549908 -2.549906)
			(end -1.549908 -2.549906)
			(stroke
				(width 0.1)
				(type default)
			)
			(layer "F.Fab")
		)
		(fp_line
			(start -1.549908 2.549906)
			(end 1.549908 2.549906)
			(stroke
				(width 0.1)
				(type default)
			)
			(layer "F.Fab")
		)
		(fp_line
			(start -1.549908 -2.549906)
			(end -1.549908 2.549906)
			(stroke
				(width 0.1)
				(type default)
			)
			(layer "F.Fab")
		)
		(fp_poly
			(pts
				(xy -1.891538 -1.999996) (xy -2.7432 -1.574292) (xy -2.7432 -2.4257)
			)
			(stroke
				(width 0)
				(type default)
			)
			(fill yes)
			(layer "F.Fab")
		)
		(fp_text user "11"
			(at 2.89687 5.385054 0)
			(unlocked yes)
			(layer "F.SilkS")
			(effects
				(font
					(size 0.635 0.4064)
					(thickness 0.1524)
				)
			)
		)
		(fp_text user "12"
			(at 2.66319 1.054354 0)
			(unlocked yes)
			(layer "F.SilkS")
			(effects
				(font
					(size 0.635 0.4064)
					(thickness 0.1524)
				)
			)
		)
		(fp_text user "20"
			(at 1.33223 -3.296666 0)
			(unlocked yes)
			(layer "F.SilkS")
			(effects
				(font
					(size 0.635 0.4064)
					(thickness 0.1524)
				)
			)
		)
		(fp_text user "21_22"
			(at -2.01803 -4.109466 0)
			(unlocked yes)
			(layer "F.SilkS")
			(effects
				(font
					(size 0.635 0.4064)
					(thickness 0.1524)
				)
			)
		)
		(fp_text user "10"
			(at -2.38379 3.007614 0)
			(unlocked yes)
			(layer "F.SilkS")
			(effects
				(font
					(size 0.635 0.4064)
					(thickness 0.1524)
				)
			)
		)
		(fp_text user "9"
			(at -2.44221 1.478534 0)
			(unlocked yes)
			(layer "F.SilkS")
			(effects
				(font
					(size 0.635 0.4064)
					(thickness 0.1524)
				)
			)
		)
		(fp_text user "12"
			(at 2.207768 2.7178 90)
			(unlocked yes)
			(layer "F.Fab")
			(effects
				(font
					(size 0.635 0.4064)
					(thickness 0.1524)
				)
			)
		)
		(fp_text user "20"
			(at 2.055368 -2.7686 90)
			(unlocked yes)
			(layer "F.Fab")
			(effects
				(font
					(size 0.635 0.4064)
					(thickness 0.1524)
				)
			)
		)
		(fp_text user "11"
			(at 1.1938 3.329432 180)
			(unlocked yes)
			(layer "F.Fab")
			(effects
				(font
					(size 0.635 0.4064)
					(thickness 0.1524)
				)
			)
		)
		(fp_text user "21_22"
			(at -0.0762 -3.401568 180)
			(unlocked yes)
			(layer "F.Fab")
			(effects
				(font
					(size 0.635 0.4064)
					(thickness 0.1524)
				)
			)
		)
		(fp_text user "10"
			(at -1.4224 3.253232 180)
			(unlocked yes)
			(layer "F.Fab")
			(effects
				(font
					(size 0.635 0.4064)
					(thickness 0.1524)
				)
			)
		)
		(fp_text user "9"
			(at -2.338832 2.5908 90)
			(unlocked yes)
			(layer "F.Fab")
			(effects
				(font
					(size 0.635 0.4064)
					(thickness 0.1524)
				)
			)
		)
		(pad "1" smd circle
			(at -1.374902 -1.999996 90)
			(size 0 0)
			(layers "F.Cu" "F.Mask" "F.Paste")
			(net "P12V_E1S_EN_0_R2")
		)
		(pad "2" smd rect
			(at -1.400048 -1.500124 90)
			(size 0.254 0.8128)
			(layers "F.Cu" "F.Mask" "F.Paste")
			(net "GND")
		)
		(pad "3" smd rect
			(at -1.400048 -0.999998 90)
			(size 0.254 0.8128)
			(layers "F.Cu" "F.Mask" "F.Paste")
			(net "GND")
		)
		(pad "4" smd rect
			(at -1.400048 -0.499872 90)
			(size 0.254 0.8128)
			(layers "F.Cu" "F.Mask" "F.Paste")
			(net "P12V_E1S_TIMER_0")
		)
		(pad "5" smd rect
			(at -1.400048 0 90)
			(size 0.254 0.8128)
			(layers "F.Cu" "F.Mask" "F.Paste")
			(net "P12V_E1S_ISET_0")
		)
		(pad "6" smd rect
			(at -1.400048 0.499872 90)
			(size 0.254 0.8128)
			(layers "F.Cu" "F.Mask" "F.Paste")
			(net "P12V_E1S_SS_0")
		)
		(pad "7" smd rect
			(at -1.400048 0.999998 90)
			(size 0.254 0.8128)
			(layers "F.Cu" "F.Mask" "F.Paste")
			(net "GND")
		)
		(pad "8" smd rect
			(at -1.400048 1.500124 90)
			(size 0.254 0.8128)
			(layers "F.Cu" "F.Mask" "F.Paste")
			(net "P12V_E1S_IMON_0")
		)
		(pad "9" smd rect
			(at -1.400048 1.999996 90)
			(size 0.254 0.8128)
			(layers "F.Cu" "F.Mask" "F.Paste")
			(net "P12V_E1S_FLTB_0")
		)
		(pad "10" smd rect
			(at -0.499872 2.400046 180)
			(size 0.254 0.8128)
			(layers "F.Cu" "F.Mask" "F.Paste")
			(net "HP_LVC3_E1S_0_HSC_PWRGD")
		)
		(pad "11" smd rect
			(at 0.499872 2.400046 180)
			(size 0.254 0.8128)
			(layers "F.Cu" "F.Mask" "F.Paste")
			(net "P12V_E1S_OV_FB_0")
		)
		(pad "12" smd rect
			(at 1.400048 1.999996 90)
			(size 0.254 0.8128)
			(layers "F.Cu" "F.Mask" "F.Paste")
			(net "P12V_E1S_AVIN_PD_0")
		)
		(pad "13" smd rect
			(at 1.400048 1.500124 90)
			(size 0.254 0.8128)
			(layers "F.Cu" "F.Mask" "F.Paste")
			(net "P12V_E1S_0")
		)
		(pad "14" smd rect
			(at 1.400048 0.999998 90)
			(size 0.254 0.8128)
			(layers "F.Cu" "F.Mask" "F.Paste")
			(net "P12V_E1S_0")
		)
		(pad "15" smd rect
			(at 1.400048 0.499872 90)
			(size 0.254 0.8128)
			(layers "F.Cu" "F.Mask" "F.Paste")
			(net "P12V_E1S_0")
		)
		(pad "16" smd rect
			(at 1.400048 0 90)
			(size 0.254 0.8128)
			(layers "F.Cu" "F.Mask" "F.Paste")
			(net "P12V_E1S_0")
		)
		(pad "17" smd rect
			(at 1.400048 -0.499872 90)
			(size 0.254 0.8128)
			(layers "F.Cu" "F.Mask" "F.Paste")
			(net "P12V_E1S_0")
		)
		(pad "18" smd rect
			(at 1.400048 -0.999998 90)
			(size 0.254 0.8128)
			(layers "F.Cu" "F.Mask" "F.Paste")
			(net "P12V_E1S_0")
		)
		(pad "19" smd rect
			(at 1.400048 -1.500124 90)
			(size 0.254 0.8128)
			(layers "F.Cu" "F.Mask" "F.Paste")
			(net "P12V_E1S_0")
		)
		(pad "20" smd rect
			(at 1.400048 -1.999996 90)
			(size 0.254 0.8128)
			(layers "F.Cu" "F.Mask" "F.Paste")
			(net "P12V_E1S_0")
		)
		(pad "21_22" smd circle
			(at 0.499872 -2.337562 90)
			(size 0 0)
			(layers "F.Cu" "F.Mask" "F.Paste")
			(net "P12V_AUX")
		)
		(pad "23" smd rect
			(at 0 -1.100074 90)
			(size 0.254 1.27)
			(layers "F.Cu" "F.Mask" "F.Paste")
			(net "P12V_AUX")
		)
		(pad "24" smd rect
			(at 0 -0.199898 90)
			(size 0.254 1.27)
			(layers "F.Cu" "F.Mask" "F.Paste")
			(net "P12V_AUX")
		)
		(pad "25" smd rect
			(at 0 0.700024 90)
			(size 0.254 1.27)
			(layers "F.Cu" "F.Mask" "F.Paste")
			(net "P12V_AUX")
		)
		(pad "26" smd rect
			(at 0 1.599946 90)
			(size 0.254 1.27)
			(layers "F.Cu" "F.Mask" "F.Paste")
			(net "P12V_AUX")
		)
	)
	(footprint ""
		(layer "F.Cu")
		(at 440.358276 -103.340916 90)
		(property "Reference" "U334"
			(at -1.397 -2.225548 90)
			(unlocked yes)
			(layer "F.SilkS")
			(effects
				(font
					(size 0.7874 0.5842)
					(thickness 0.1524)
				)
				(justify left)
			)
		)
		(property "Value" ""
			(at 0 0 90)
			(layer "F.Fab")
			(effects
				(font
					(size 1.27 1.27)
				)
			)
		)
		(duplicate_pad_numbers_are_jumpers no)
		(fp_line
			(start 1.733296 -1.549908)
			(end 0.660908 -1.549908)
			(stroke
				(width 0.1524)
				(type default)
			)
			(layer "F.SilkS")
		)
		(fp_line
			(start 0.660908 -1.549908)
			(end 0 -0.889)
			(stroke
				(width 0.1524)
				(type default)
			)
			(layer "F.SilkS")
		)
		(fp_line
			(start -0.660908 -1.549908)
			(end -1.733296 -1.549908)
			(stroke
				(width 0.1524)
				(type default)
			)
			(layer "F.SilkS")
		)
		(fp_line
			(start -1.733296 -1.549908)
			(end -1.733296 1.549908)
			(stroke
				(width 0.1524)
				(type default)
			)
			(layer "F.SilkS")
		)
		(fp_line
			(start 0 -0.889)
			(end -0.660908 -1.549908)
			(stroke
				(width 0.1524)
				(type default)
			)
			(layer "F.SilkS")
		)
		(fp_line
			(start 1.733296 1.549908)
			(end 1.733296 -1.549908)
			(stroke
				(width 0.1524)
				(type default)
			)
			(layer "F.SilkS")
		)
		(fp_line
			(start -1.733296 1.549908)
			(end 1.733296 1.549908)
			(stroke
				(width 0.1524)
				(type default)
			)
			(layer "F.SilkS")
		)
		(fp_poly
			(pts
				(xy -2.10693 -2.095246) (xy -2.46634 -1.73609) (xy -1.927352 -1.556512)
			)
			(stroke
				(width 0)
				(type default)
			)
			(fill yes)
			(layer "F.SilkS")
		)
		(fp_line
			(start 0.849884 -1.549908)
			(end -0.849884 -1.549908)
			(stroke
				(width 0.1)
				(type default)
			)
			(layer "F.Fab")
		)
		(fp_line
			(start -0.849884 -1.549908)
			(end -0.849884 1.549908)
			(stroke
				(width 0.1)
				(type default)
			)
			(layer "F.Fab")
		)
		(fp_line
			(start 0.849884 1.549908)
			(end 0.849884 -1.549908)
			(stroke
				(width 0.1)
				(type default)
			)
			(layer "F.Fab")
		)
		(fp_line
			(start -0.849884 1.549908)
			(end 0.849884 1.549908)
			(stroke
				(width 0.1)
				(type default)
			)
			(layer "F.Fab")
		)
		(fp_poly
			(pts
				(xy -2.4384 -1.20396) (xy -2.4384 -0.69596) (xy -1.9304 -0.94996)
			)
			(stroke
				(width 0)
				(type default)
			)
			(fill yes)
			(layer "F.Fab")
		)
		(pad "1" smd rect
			(at -1.199896 -0.94996)
			(size 0.5588 0.8128)
			(layers "F.Cu" "F.Mask" "F.Paste")
			(net "HP_LVC3_OCP_V3_1_PWRGD_R2")
		)
		(pad "2" smd rect
			(at -1.199896 0)
			(size 0.5588 0.8128)
			(layers "F.Cu" "F.Mask" "F.Paste")
			(net "OCP_SFF_AUX_PWR_PLD_EN_R")
		)
		(pad "3" smd rect
			(at -1.199896 0.94996)
			(size 0.5588 0.8128)
			(layers "F.Cu" "F.Mask" "F.Paste")
			(net "GND")
		)
		(pad "4" smd rect
			(at 1.199896 0.94996)
			(size 0.5588 0.8128)
			(layers "F.Cu" "F.Mask" "F.Paste")
			(net "OCP_SFF_AUX_PWR_EN_R2")
		)
		(pad "5" smd rect
			(at 1.199896 -0.94996)
			(size 0.5588 0.8128)
			(layers "F.Cu" "F.Mask" "F.Paste")
			(net "P3V3_AUX")
		)
	)
)
